# TIMECARD (Time Appliance Project (Time Card)) — schematic netlist excerpt (pin names and nets, part order shuffled) for the footprints in the layout excerpt that follows; sources: Cadence DE-HDL packaged netlist, KiCad conversion of R4006-B0001-02_R01.brd

DS14  LED_4P_V14  pkg SMC_DS4_098X039  page 26
  \1\  = UNNAMED_14_LED4PV14_I265_1
  \2\  = XP3R3V_FPGA
  \3\  = UNNAMED_14_LED4PV14_I265_3
  \4\  = UNNAMED_14_LED4PV14_I265_4

(kicad_pcb
	(version 20260206)
	(generator "pcbnew")
	(generator_version "10.0")
	(general
		(thickness 1.6)
		(legacy_teardrops no)
	)
	(paper "A4")
	(title_block
		(title "timecard-production-celestica-r4006 — R4006-B0001-02_R01.brd")
		(comment 1 "Time Appliance Project (Time Card) / footprints 498-498 of 1113")
	)
	(layers
		(0 "F.Cu" signal "TOP")
		(4 "In1.Cu" signal "L02_GND1")
		(6 "In2.Cu" signal "L03_SIG1")
		(8 "In3.Cu" signal "L04_GND2")
		(10 "In4.Cu" signal "L05_VCC1")
		(12 "In5.Cu" signal "L06_VCC2")
		(14 "In6.Cu" signal "L07_GND3")
		(16 "In7.Cu" signal "L08_SIG2")
		(18 "In8.Cu" signal "L09_GND4")
		(2 "B.Cu" signal "BOTTOM")
		(9 "F.Adhes" user "F.Adhesive")
		(11 "B.Adhes" user "B.Adhesive")
		(13 "F.Paste" user "Package Geometry/Pastemask Top")
		(15 "B.Paste" user "Package Geometry/Pastemask Bottom")
		(5 "F.SilkS" user "Ref Des/Silkscreen Top")
		(7 "B.SilkS" user "Ref Des/Silkscreen Bottom")
		(1 "F.Mask" user "Board Geometry/Soldermask Top")
		(3 "B.Mask" user "Board Geometry/Soldermask Bottom")
		(17 "Dwgs.User" user "User.Drawings")
		(19 "Cmts.User" user "User.Comments")
		(21 "Eco1.User" user "User.Eco1")
		(23 "Eco2.User" user "User.Eco2")
		(25 "Edge.Cuts" user "Board Geometry/Outline")
		(27 "Margin" user)
		(31 "F.CrtYd" user "Package Geometry/Place Bound Top")
		(29 "B.CrtYd" user "Package Geometry/Place Bound Bottom")
		(35 "F.Fab" user "Ref Des/Assembly Top")
		(33 "B.Fab" user "Ref Des/Assembly Bottom")
	)
	(footprint ""
		(layer "F.Cu")
		(at 1.500124 -39.099998 90)
		(property "Reference" "DS14"
			(at 2.770632 1.293876 0)
			(unlocked yes)
			(layer "F.SilkS")
			(effects
				(font
					(size 0.7874 0.5842)
					(thickness 0.1524)
				)
			)
		)
		(property "Value" ""
			(at 0 0 90)
			(layer "F.Fab")
			(effects
				(font
					(size 1.27 1.27)
				)
			)
		)
		(property "User Part Number" "PARTNUM*"
			(at 0.015494 4.486402 90)
			(unlocked yes)
			(layer "Cmts.User")
			(hide yes)
			(effects
				(font
					(size 0.7874 0.5842)
					(thickness 0.1524)
				)
			)
		)
		(property "Device Type" "LED_4P_V14-G170-10189-01"
			(at 0.015494 3.292602 90)
			(unlocked yes)
			(layer "F.Fab")
			(hide yes)
			(effects
				(font
					(size 0.7874 0.5842)
					(thickness 0.1524)
				)
			)
		)
		(duplicate_pad_numbers_are_jumpers no)
		(fp_line
			(start 1.378966 -0.829056)
			(end -1.378966 -0.829056)
			(stroke
				(width 0.1)
				(type default)
			)
			(layer "F.SilkS")
		)
		(fp_line
			(start -1.378966 -0.829056)
			(end -1.378966 -0.452628)
			(stroke
				(width 0.1)
				(type default)
			)
			(layer "F.SilkS")
		)
		(fp_line
			(start 1.998218 -0.452628)
			(end 1.378966 -0.452628)
			(stroke
				(width 0.1)
				(type default)
			)
			(layer "F.SilkS")
		)
		(fp_line
			(start 1.378966 -0.452628)
			(end 1.378966 -0.829056)
			(stroke
				(width 0.1)
				(type default)
			)
			(layer "F.SilkS")
		)
		(fp_line
			(start -1.378966 -0.452628)
			(end -1.998218 -0.452628)
			(stroke
				(width 0.1)
				(type default)
			)
			(layer "F.SilkS")
		)
		(fp_line
			(start -1.998218 -0.452628)
			(end -1.998218 1.103884)
			(stroke
				(width 0.1)
				(type default)
			)
			(layer "F.SilkS")
		)
		(fp_line
			(start 1.998218 1.103884)
			(end 1.998218 -0.452628)
			(stroke
				(width 0.1)
				(type default)
			)
			(layer "F.SilkS")
		)
		(fp_line
			(start -1.998218 1.103884)
			(end 1.998218 1.103884)
			(stroke
				(width 0.1)
				(type default)
			)
			(layer "F.SilkS")
		)
		(fp_poly
			(pts
				(xy 0.918464 -1.698498) (xy 1.223264 -1.46939) (xy 0.994664 -1.46939) (xy 0.994664 -1.24079) (xy 0.842264 -1.24079)
				(xy 0.842264 -1.46939) (xy 0.613664 -1.46939)
			)
			(stroke
				(width 0)
				(type default)
			)
			(fill yes)
			(layer "F.SilkS")
		)
		(fp_poly
			(pts
				(xy -0.73406 -1.677416) (xy -0.42926 -1.448308) (xy -0.65786 -1.448308) (xy -0.65786 -1.219708)
				(xy -0.81026 -1.219708) (xy -0.81026 -1.448308) (xy -1.03886 -1.448308)
			)
			(stroke
				(width 0)
				(type default)
			)
			(fill yes)
			(layer "F.SilkS")
		)
		(fp_poly
			(pts
				(xy -2.252218 1.357884) (xy -2.252218 -0.706628) (xy -1.632966 -0.706628) (xy -1.632966 -1.083056)
				(xy 1.632966 -1.083056) (xy 1.632966 -0.706628) (xy 2.252218 -0.706628) (xy 2.252218 1.357884)
			)
			(stroke
				(width 0)
				(type default)
			)
			(fill no)
			(layer "F.CrtYd")
		)
		(fp_line
			(start 1.124966 -0.575056)
			(end -1.124966 -0.575056)
			(stroke
				(width 0.1)
				(type default)
			)
			(layer "F.Fab")
		)
		(fp_line
			(start -1.124966 -0.575056)
			(end -1.124966 -0.075184)
			(stroke
				(width 0.1)
				(type default)
			)
			(layer "F.Fab")
		)
		(fp_line
			(start 1.325118 -0.075184)
			(end 1.124966 -0.075184)
			(stroke
				(width 0.1)
				(type default)
			)
			(layer "F.Fab")
		)
		(fp_line
			(start 1.124966 -0.075184)
			(end 1.124966 -0.575056)
			(stroke
				(width 0.1)
				(type default)
			)
			(layer "F.Fab")
		)
		(fp_line
			(start -1.124966 -0.075184)
			(end -1.325118 -0.075184)
			(stroke
				(width 0.1)
				(type default)
			)
			(layer "F.Fab")
		)
		(fp_line
			(start -1.325118 -0.075184)
			(end -1.325118 0.574802)
			(stroke
				(width 0.1)
				(type default)
			)
			(layer "F.Fab")
		)
		(fp_line
			(start 1.325118 0.574802)
			(end 1.325118 -0.075184)
			(stroke
				(width 0.1)
				(type default)
			)
			(layer "F.Fab")
		)
		(fp_line
			(start -1.325118 0.574802)
			(end 1.325118 0.574802)
			(stroke
				(width 0.1)
				(type default)
			)
			(layer "F.Fab")
		)
		(fp_poly
			(pts
				(xy 0.918464 -1.698498) (xy 1.223264 -1.46939) (xy 0.994664 -1.46939) (xy 0.994664 -1.24079) (xy 0.842264 -1.24079)
				(xy 0.842264 -1.46939) (xy 0.613664 -1.46939)
			)
			(stroke
				(width 0)
				(type default)
			)
			(fill yes)
			(layer "F.Fab")
		)
		(fp_poly
			(pts
				(xy -0.73406 -1.677416) (xy -0.42926 -1.448308) (xy -0.65786 -1.448308) (xy -0.65786 -1.219708)
				(xy -0.81026 -1.219708) (xy -0.81026 -1.448308) (xy -1.03886 -1.448308)
			)
			(stroke
				(width 0)
				(type default)
			)
			(fill yes)
			(layer "F.Fab")
		)
		(fp_text user "4"
			(at 2.778252 -0.611124 0)
			(unlocked yes)
			(layer "F.SilkS")
			(effects
				(font
					(size 0.635 0.4064)
					(thickness 0.1524)
				)
			)
		)
		(fp_text user "1"
			(at -2.37617 0.376936 90)
			(unlocked yes)
			(layer "F.SilkS")
			(effects
				(font
					(size 0.7874 0.5842)
					(thickness 0.1524)
				)
			)
		)
		(fp_text user "2"
			(at -1.158748 1.420876 0)
			(unlocked yes)
			(layer "F.SilkS")
			(effects
				(font
					(size 0.635 0.4064)
					(thickness 0.1524)
				)
			)
		)
		(fp_text user "3"
			(at 1.305052 1.547876 0)
			(unlocked yes)
			(layer "F.SilkS")
			(effects
				(font
					(size 0.635 0.4064)
					(thickness 0.1524)
				)
			)
		)
		(fp_text user "4"
			(at 1.92532 1.166876 0)
			(unlocked yes)
			(layer "F.Fab")
			(effects
				(font
					(size 0.7874 0.5842)
					(thickness 0.1524)
				)
			)
		)
		(fp_text user "3"
			(at 0.738632 1.166876 0)
			(unlocked yes)
			(layer "F.Fab")
			(effects
				(font
					(size 0.7874 0.5842)
					(thickness 0.1524)
				)
			)
		)
		(fp_text user "2"
			(at -0.531368 1.293876 0)
			(unlocked yes)
			(layer "F.Fab")
			(effects
				(font
					(size 0.7874 0.5842)
					(thickness 0.1524)
				)
			)
		)
		(fp_text user "1"
			(at -1.674368 1.293876 0)
			(unlocked yes)
			(layer "F.Fab")
			(effects
				(font
					(size 0.7874 0.5842)
					(thickness 0.1524)
				)
			)
		)
		(pad "1" smd rect
			(at -1.325118 0.245872 90)
			(size 0.8382 0.889)
			(layers "F.Cu" "F.Mask" "F.Paste")
			(net "UNNAMED_14_LED4PV14_I265_1")
		)
		(pad "2" smd rect
			(at -0.424942 0.595884 90)
			(size 0.4572 0.508)
			(layers "F.Cu" "F.Mask" "F.Paste")
			(net "XP3R3V_FPGA")
		)
		(pad "3" smd rect
			(at 0.424942 0.595884 90)
			(size 0.4572 0.508)
			(layers "F.Cu" "F.Mask" "F.Paste")
			(net "UNNAMED_14_LED4PV14_I265_3")
		)
		(pad "4" smd rect
			(at 1.325118 0.245872 90)
			(size 0.8382 0.889)
			(layers "F.Cu" "F.Mask" "F.Paste")
			(net "UNNAMED_14_LED4PV14_I265_4")
		)
	)
)
